(kicad_pcb
	(version 20241229)
	(generator "pcbnew")
	(generator_version "9.0")
	(general
		(thickness 1.59)
		(legacy_teardrops no)
	)
	(paper "A3")
	(title_block
		(title "usb-c-power-adapter")
		(date "2025-06-24")
		(rev "1.1.2")
		(company "Antmicro")
		(comment 9 "footprints 15-21 of 122")
	)
	(layers
		(0 "F.Cu" signal)
		(4 "In1.Cu" signal)
		(6 "In2.Cu" signal)
		(2 "B.Cu" signal)
		(9 "F.Adhes" user "F.Adhesive")
		(11 "B.Adhes" user "B.Adhesive")
		(13 "F.Paste" user)
		(15 "B.Paste" user)
		(5 "F.SilkS" user "F.Silkscreen")
		(7 "B.SilkS" user "B.Silkscreen")
		(1 "F.Mask" user)
		(3 "B.Mask" user)
		(17 "Dwgs.User" user "User.Drawings")
		(19 "Cmts.User" user "User.Comments")
		(21 "Eco1.User" user "User.Eco1")
		(23 "Eco2.User" user "User.Eco2")
		(25 "Edge.Cuts" user)
		(27 "Margin" user)
		(31 "F.CrtYd" user "F.Courtyard")
		(29 "B.CrtYd" user "B.Courtyard")
		(35 "F.Fab" user)
		(33 "B.Fab" user)
	)
	(footprint "antmicro-footprints:R_0402_1005Metric"
		(layer "F.Cu")
		(at 99.046136 72.35 90)
		(descr "Resistor SMD 0402")
		(tags "resistor SMD 0402")
		(property "Reference" "R25"
			(at -8.93 -0.570136 0)
			(layer "B.SilkS")
			(effects
				(font
					(size 0.7 0.7)
					(thickness 0.15)
				)
				(justify left bottom mirror)
			)
		)
		(property "Value" "R_470R_0402"
			(at -1.011843 1.772047 90)
			(layer "F.Fab")
			(effects
				(font
					(size 0.7 0.7)
					(thickness 0.15)
				)
				(justify left bottom)
			)
		)
		(property "Datasheet" "https://www.bourns.com/docs/product-datasheets/cr.pdf"
			(at 0 0 90)
			(layer "F.Fab")
			(hide yes)
			(effects
				(font
					(size 1.27 1.27)
					(thickness 0.15)
				)
			)
		)
		(property "Description" "SMD Chip Resistor, 470 ohm, ± 1%, 62.5 mW, 0402 [1005 Metric], Thick Film, General Purpose"
			(at 0 0 90)
			(layer "F.Fab")
			(hide yes)
			(effects
				(font
					(size 1.27 1.27)
					(thickness 0.15)
				)
			)
		)
		(property "MPN" "CR0402-FX-4700GLF"
			(at 0 0 90)
			(unlocked yes)
			(layer "F.Fab")
			(hide yes)
			(effects
				(font
					(size 1 1)
					(thickness 0.15)
				)
			)
		)
		(property "Manufacturer" "Bourns"
			(at 0 0 90)
			(unlocked yes)
			(layer "F.Fab")
			(hide yes)
			(effects
				(font
					(size 1 1)
					(thickness 0.15)
				)
			)
		)
		(property "License" "Apache-2.0"
			(at 0 0 90)
			(unlocked yes)
			(layer "F.Fab")
			(hide yes)
			(effects
				(font
					(size 1 1)
					(thickness 0.15)
				)
			)
		)
		(property "Author" "Antmicro"
			(at 0 0 90)
			(unlocked yes)
			(layer "F.Fab")
			(hide yes)
			(effects
				(font
					(size 1 1)
					(thickness 0.15)
				)
			)
		)
		(property "Val" "470R"
			(at 0 0 90)
			(unlocked yes)
			(layer "F.Fab")
			(hide yes)
			(effects
				(font
					(size 1 1)
					(thickness 0.15)
				)
			)
		)
		(property "Tolerance" "1%"
			(at 0 0 90)
			(unlocked yes)
			(layer "F.Fab")
			(hide yes)
			(effects
				(font
					(size 1 1)
					(thickness 0.15)
				)
			)
		)
		(sheetname "/USB PD/")
		(sheetfile "usb_pd.kicad_sch")
		(attr smd)
		(fp_rect
			(start -0.925 -0.47)
			(end 0.925 0.47)
			(stroke
				(width 0.05)
				(type default)
			)
			(fill no)
			(layer "F.CrtYd")
		)
		(fp_rect
			(start -0.5 -0.25)
			(end 0.5 0.25)
			(stroke
				(width 0.15)
				(type solid)
			)
			(fill no)
			(layer "F.Fab")
		)
		(pad "1" smd roundrect
			(at -0.48 0 90)
			(size 0.59 0.64)
			(layers "F.Cu" "F.Mask" "F.Paste")
			(roundrect_rratio 0.25)
			(net 66 "Net-(D6-A)")
			(pintype "passive")
		)
		(pad "2" smd roundrect
			(at 0.48 0 90)
			(size 0.59 0.64)
			(layers "F.Cu" "F.Mask" "F.Paste")
			(roundrect_rratio 0.25)
			(net 25 "+5V")
			(pintype "passive")
		)
	)
	(footprint "antmicro-footprints:R_0402_1005Metric"
		(layer "F.Cu")
		(at 96.8 80.3 90)
		(descr "Resistor SMD 0402")
		(tags "resistor SMD 0402")
		(property "Reference" "R13"
			(at -2.8849 6.0514 180)
			(layer "B.SilkS")
			(effects
				(font
					(size 0.7 0.7)
					(thickness 0.15)
				)
				(justify left bottom mirror)
			)
		)
		(property "Value" "R_100k_0402"
			(at -1.011843 1.772047 90)
			(layer "F.Fab")
			(effects
				(font
					(size 0.7 0.7)
					(thickness 0.15)
				)
				(justify left bottom)
			)
		)
		(property "Datasheet" "https://www.bourns.com/docs/product-datasheets/cr.pdf"
			(at 0 0 90)
			(layer "F.Fab")
			(hide yes)
			(effects
				(font
					(size 1.27 1.27)
					(thickness 0.15)
				)
			)
		)
		(property "Description" "SMD Chip Resistor, 100 kohm, ± 1%, 62.5 mW, 0402 [1005 Metric], Thick Film, General Purpose"
			(at 0 0 90)
			(layer "F.Fab")
			(hide yes)
			(effects
				(font
					(size 1.27 1.27)
					(thickness 0.15)
				)
			)
		)
		(property "Manufacturer" "Bourns"
			(at 0 0 90)
			(unlocked yes)
			(layer "F.Fab")
			(hide yes)
			(effects
				(font
					(size 1 1)
					(thickness 0.15)
				)
			)
		)
		(property "MPN" "CR0402-FX-1003GLF"
			(at 0 0 90)
			(unlocked yes)
			(layer "F.Fab")
			(hide yes)
			(effects
				(font
					(size 1 1)
					(thickness 0.15)
				)
			)
		)
		(property "Val" "100k"
			(at 0 0 90)
			(unlocked yes)
			(layer "F.Fab")
			(hide yes)
			(effects
				(font
					(size 1 1)
					(thickness 0.15)
				)
			)
		)
		(property "License" "Apache-2.0"
			(at 0 0 90)
			(unlocked yes)
			(layer "F.Fab")
			(hide yes)
			(effects
				(font
					(size 1 1)
					(thickness 0.15)
				)
			)
		)
		(property "Author" "Antmicro"
			(at 0 0 90)
			(unlocked yes)
			(layer "F.Fab")
			(hide yes)
			(effects
				(font
					(size 1 1)
					(thickness 0.15)
				)
			)
		)
		(property "Tolerance" "1%"
			(at 0 0 90)
			(unlocked yes)
			(layer "F.Fab")
			(hide yes)
			(effects
				(font
					(size 1 1)
					(thickness 0.15)
				)
			)
		)
		(sheetname "/DC-DC Converters/")
		(sheetfile "dc-dc_converters.kicad_sch")
		(attr smd)
		(fp_rect
			(start -0.925 -0.47)
			(end 0.925 0.47)
			(stroke
				(width 0.05)
				(type default)
			)
			(fill no)
			(layer "F.CrtYd")
		)
		(fp_rect
			(start -0.5 -0.25)
			(end 0.5 0.25)
			(stroke
				(width 0.15)
				(type solid)
			)
			(fill no)
			(layer "F.Fab")
		)
		(pad "1" smd roundrect
			(at -0.48 0 90)
			(size 0.59 0.64)
			(layers "F.Cu" "F.Mask" "F.Paste")
			(roundrect_rratio 0.25)
			(net 48 "Net-(U2-P_{GOOD})")
			(pintype "passive")
		)
		(pad "2" smd roundrect
			(at 0.48 0 90)
			(size 0.59 0.64)
			(layers "F.Cu" "F.Mask" "F.Paste")
			(roundrect_rratio 0.25)
			(net 10 "/DC-DC Converters/VDD_12V_DCDC")
			(pintype "passive")
		)
	)
	(footprint "antmicro-footprints:TP_SMD_0.75mm"
		(layer "F.Cu")
		(at 86.4 70)
		(property "Reference" "TP2"
			(at -9.184 -5.134 0)
			(layer "F.SilkS")
			(hide yes)
			(effects
				(font
					(size 0.7 0.7)
					(thickness 0.15)
				)
				(justify left bottom)
			)
		)
		(property "Value" "TP_0.75mm_SMD"
			(at 0 1.2 0)
			(layer "F.Fab")
			(effects
				(font
					(size 0.7 0.7)
					(thickness 0.15)
				)
				(justify left bottom)
			)
		)
		(property "Description" "SMT test point"
			(at 0 0 0)
			(layer "F.Fab")
			(hide yes)
			(effects
				(font
					(size 1.27 1.27)
					(thickness 0.15)
				)
			)
		)
		(property "MPN" ""
			(at 0 0 0)
			(unlocked yes)
			(layer "F.Fab")
			(hide yes)
			(effects
				(font
					(size 1 1)
					(thickness 0.15)
				)
			)
		)
		(property "Manufacturer" ""
			(at 0 0 0)
			(unlocked yes)
			(layer "F.Fab")
			(hide yes)
			(effects
				(font
					(size 1 1)
					(thickness 0.15)
				)
			)
		)
		(property "Author" "Antmicro"
			(at 0 0 0)
			(unlocked yes)
			(layer "F.Fab")
			(hide yes)
			(effects
				(font
					(size 1 1)
					(thickness 0.15)
				)
			)
		)
		(property "License" "Apache-2.0"
			(at 0 0 0)
			(unlocked yes)
			(layer "F.Fab")
			(hide yes)
			(effects
				(font
					(size 1 1)
					(thickness 0.15)
				)
			)
		)
		(sheetname "/USB PD/")
		(sheetfile "usb_pd.kicad_sch")
		(attr exclude_from_bom)
		(fp_circle
			(center 0 0)
			(end 0.475 0)
			(stroke
				(width 0.05)
				(type default)
			)
			(fill no)
			(layer "F.CrtYd")
		)
		(pad "1" smd circle
			(at 0 0)
			(size 0.75 0.75)
			(layers "F.Cu" "F.Mask")
			(net 38 "/USB PD/SCL")
			(pinfunction "1")
			(pintype "passive")
		)
	)
	(footprint "antmicro-footprints:C_0805_2012Metric"
		(layer "F.Cu")
		(at 87.4 84.7 90)
		(descr "Capacitor SMD 0805")
		(tags "capacitor SMD 0805")
		(property "Reference" "C16"
			(at -3.69 -4.254 90)
			(layer "F.SilkS")
			(effects
				(font
					(size 0.7 0.7)
					(thickness 0.15)
				)
				(justify left bottom)
			)
		)
		(property "Value" "C_10u_0805_35V"
			(at -2.055717 1.963152 90)
			(layer "F.Fab")
			(effects
				(font
					(size 0.7 0.7)
					(thickness 0.15)
				)
				(justify left bottom)
			)
		)
		(property "Datasheet" "https://www.murata.com/products/productdetail?partno=GRM21BR6YA106KE43%23"
			(at 0 0 90)
			(layer "F.Fab")
			(hide yes)
			(effects
				(font
					(size 1.27 1.27)
					(thickness 0.15)
				)
			)
		)
		(property "Description" "SMD Multilayer Ceramic Capacitor, 10 µF, 35 V, 0805 [2012 Metric], ± 10%, X5R, GRM Series"
			(at 0 0 90)
			(layer "F.Fab")
			(hide yes)
			(effects
				(font
					(size 1.27 1.27)
					(thickness 0.15)
				)
			)
		)
		(property "MPN" "GRM21BR6YA106KE43L"
			(at 0 0 90)
			(unlocked yes)
			(layer "F.Fab")
			(hide yes)
			(effects
				(font
					(size 1 1)
					(thickness 0.15)
				)
			)
		)
		(property "Manufacturer" "Murata"
			(at 0 0 90)
			(unlocked yes)
			(layer "F.Fab")
			(hide yes)
			(effects
				(font
					(size 1 1)
					(thickness 0.15)
				)
			)
		)
		(property "License" "Apache-2.0"
			(at 0 0 90)
			(unlocked yes)
			(layer "F.Fab")
			(hide yes)
			(effects
				(font
					(size 1 1)
					(thickness 0.15)
				)
			)
		)
		(property "Author" "Antmicro"
			(at 0 0 90)
			(unlocked yes)
			(layer "F.Fab")
			(hide yes)
			(effects
				(font
					(size 1 1)
					(thickness 0.15)
				)
			)
		)
		(property "Val" "10u"
			(at 0 0 90)
			(unlocked yes)
			(layer "F.Fab")
			(hide yes)
			(effects
				(font
					(size 1 1)
					(thickness 0.15)
				)
			)
		)
		(property "Voltage" "35V"
			(at 0 0 90)
			(unlocked yes)
			(layer "F.Fab")
			(hide yes)
			(effects
				(font
					(size 1 1)
					(thickness 0.15)
				)
			)
		)
		(property "Dielectric" ""
			(at 0 0 90)
			(unlocked yes)
			(layer "F.Fab")
			(hide yes)
			(effects
				(font
					(size 1 1)
					(thickness 0.15)
				)
			)
		)
		(property "Public" "False"
			(at 0 0 90)
			(unlocked yes)
			(layer "F.Fab")
			(hide yes)
			(effects
				(font
					(size 1 1)
					(thickness 0.15)
				)
			)
		)
		(sheetname "/DC-DC Converters/")
		(sheetfile "dc-dc_converters.kicad_sch")
		(attr smd)
		(fp_line
			(start -0.3 -0.7)
			(end 0.3 -0.7)
			(stroke
				(width 0.15)
				(type solid)
			)
			(layer "F.SilkS")
		)
		(fp_line
			(start -0.3 0.7)
			(end 0.3 0.7)
			(stroke
				(width 0.15)
				(type solid)
			)
			(layer "F.SilkS")
		)
		(fp_rect
			(start 1.95 -0.9)
			(end -1.95 0.9)
			(stroke
				(width 0.05)
				(type default)
			)
			(fill no)
			(layer "F.CrtYd")
		)
		(fp_rect
			(start -0.95 -0.675)
			(end 0.95 0.675)
			(stroke
				(width 0.15)
				(type solid)
			)
			(fill no)
			(layer "F.Fab")
		)
		(pad "1" smd roundrect
			(at -1.1 0 90)
			(size 1.2 1.3)
			(layers "F.Cu" "F.Mask" "F.Paste")
			(roundrect_rratio 0.25)
			(net 2 "GND")
			(pintype "passive")
		)
		(pad "2" smd roundrect
			(at 1.1 0 90)
			(size 1.2 1.3)
			(layers "F.Cu" "F.Mask" "F.Paste")
			(roundrect_rratio 0.25)
			(net 12 "Net-(U2-V_{CIN})")
			(pintype "passive")
		)
	)
	(footprint "antmicro-footprints:TP_SMD_0.75mm"
		(layer "F.Cu")
		(at 87.4 70)
		(property "Reference" "TP1"
			(at 7.342 -2.086 0)
			(layer "F.SilkS")
			(hide yes)
			(effects
				(font
					(size 0.7 0.7)
					(thickness 0.15)
				)
				(justify left bottom)
			)
		)
		(property "Value" "TP_0.75mm_SMD"
			(at 0 1.2 0)
			(layer "F.Fab")
			(effects
				(font
					(size 0.7 0.7)
					(thickness 0.15)
				)
				(justify left bottom)
			)
		)
		(property "Description" "SMT test point"
			(at 0 0 0)
			(layer "F.Fab")
			(hide yes)
			(effects
				(font
					(size 1.27 1.27)
					(thickness 0.15)
				)
			)
		)
		(property "MPN" ""
			(at 0 0 0)
			(unlocked yes)
			(layer "F.Fab")
			(hide yes)
			(effects
				(font
					(size 1 1)
					(thickness 0.15)
				)
			)
		)
		(property "Manufacturer" ""
			(at 0 0 0)
			(unlocked yes)
			(layer "F.Fab")
			(hide yes)
			(effects
				(font
					(size 1 1)
					(thickness 0.15)
				)
			)
		)
		(property "Author" "Antmicro"
			(at 0 0 0)
			(unlocked yes)
			(layer "F.Fab")
			(hide yes)
			(effects
				(font
					(size 1 1)
					(thickness 0.15)
				)
			)
		)
		(property "License" "Apache-2.0"
			(at 0 0 0)
			(unlocked yes)
			(layer "F.Fab")
			(hide yes)
			(effects
				(font
					(size 1 1)
					(thickness 0.15)
				)
			)
		)
		(sheetname "/USB PD/")
		(sheetfile "usb_pd.kicad_sch")
		(attr exclude_from_bom)
		(fp_circle
			(center 0 0)
			(end 0.475 0)
			(stroke
				(width 0.05)
				(type default)
			)
			(fill no)
			(layer "F.CrtYd")
		)
		(pad "1" smd circle
			(at 0 0)
			(size 0.75 0.75)
			(layers "F.Cu" "F.Mask")
			(net 37 "/USB PD/SDA")
			(pinfunction "1")
			(pintype "passive")
		)
	)
	(footprint "antmicro-footprints:D_SOD-323F"
		(layer "F.Cu")
		(at 91.9 72.1 180)
		(property "Reference" "D1"
			(at -1.2 2.7 0)
			(layer "F.SilkS")
			(effects
				(font
					(size 0.7 0.7)
					(thickness 0.15)
				)
				(justify right bottom)
			)
		)
		(property "Value" "PMEG6002EJ,115"
			(at -1.7 1.899 0)
			(layer "F.Fab")
			(effects
				(font
					(size 0.7 0.7)
					(thickness 0.15)
				)
				(justify right bottom)
			)
		)
		(property "Datasheet" "https://assets.nexperia.com/documents/data-sheet/PMEG6002EJ.pdf"
			(at 0 0 180)
			(layer "F.Fab")
			(hide yes)
			(effects
				(font
					(size 1.27 1.27)
					(thickness 0.15)
				)
			)
		)
		(property "Description" "Schottky Rectifier, Low VF, 60 V, 200 mA, Single, SOD-323F, 2 Pins, 600 mV"
			(at 0 0 180)
			(layer "F.Fab")
			(hide yes)
			(effects
				(font
					(size 1.27 1.27)
					(thickness 0.15)
				)
			)
		)
		(property "MPN" "PMEG6002EJ,115"
			(at 0 0 180)
			(unlocked yes)
			(layer "F.Fab")
			(hide yes)
			(effects
				(font
					(size 1 1)
					(thickness 0.15)
				)
			)
		)
		(property "Manufacturer" "Nexperia"
			(at 0 0 180)
			(unlocked yes)
			(layer "F.Fab")
			(hide yes)
			(effects
				(font
					(size 1 1)
					(thickness 0.15)
				)
			)
		)
		(property "Author" "Antmicro"
			(at 0 0 180)
			(unlocked yes)
			(layer "F.Fab")
			(hide yes)
			(effects
				(font
					(size 1 1)
					(thickness 0.15)
				)
			)
		)
		(property "License" "Apache-2.0"
			(at 0 0 180)
			(unlocked yes)
			(layer "F.Fab")
			(hide yes)
			(effects
				(font
					(size 1 1)
					(thickness 0.15)
				)
			)
		)
		(sheetname "/USB PD/")
		(sheetfile "usb_pd.kicad_sch")
		(attr smd)
		(fp_line
			(start 0.973 0.749)
			(end 0.623 0.749)
			(stroke
				(width 0.15)
				(type solid)
			)
			(layer "F.SilkS")
		)
		(fp_line
			(start 0.973 0.451)
			(end 0.973 0.749)
			(stroke
				(width 0.15)
				(type solid)
			)
			(layer "F.SilkS")
		)
		(fp_line
			(start 0.973 -0.749)
			(end 0.973 -0.449)
			(stroke
				(width 0.15)
				(type solid)
			)
			(layer "F.SilkS")
		)
		(fp_line
			(start 0.623 -0.749)
			(end 0.973 -0.749)
			(stroke
				(width 0.15)
				(type solid)
			)
			(layer "F.SilkS")
		)
		(fp_line
			(start -0.5 -0.425)
			(end -0.5 0.425)
			(stroke
				(width 0.15)
				(type solid)
			)
			(layer "F.SilkS")
		)
		(fp_line
			(start -0.625 0.749)
			(end -0.975 0.749)
			(stroke
				(width 0.15)
				(type solid)
			)
			(layer "F.SilkS")
		)
		(fp_line
			(start -0.625 -0.749)
			(end -0.975 -0.749)
			(stroke
				(width 0.15)
				(type solid)
			)
			(layer "F.SilkS")
		)
		(fp_line
			(start -0.975 0.749)
			(end -0.975 0.451)
			(stroke
				(width 0.15)
				(type solid)
			)
			(layer "F.SilkS")
		)
		(fp_line
			(start -0.975 -0.749)
			(end -0.975 -0.449)
			(stroke
				(width 0.15)
				(type solid)
			)
			(layer "F.SilkS")
		)
		(fp_rect
			(start -1.55 -0.95)
			(end 1.55 0.95)
			(stroke
				(width 0.05)
				(type solid)
			)
			(fill no)
			(layer "F.CrtYd")
		)
		(fp_rect
			(start -1.25 -0.676)
			(end 1.245365 0.676)
			(stroke
				(width 0.1)
				(type solid)
			)
			(fill no)
			(layer "F.Fab")
		)
		(pad "1" smd roundrect
			(at -1.051 0.001 180)
			(size 0.8 0.6)
			(layers "F.Cu" "F.Mask" "F.Paste")
			(roundrect_rratio 0.15)
			(net 63 "Net-(D1-C)")
			(pinfunction "C")
			(pintype "passive")
		)
		(pad "2" smd roundrect
			(at 1.05 0.001 180)
			(size 0.8 0.6)
			(layers "F.Cu" "F.Mask" "F.Paste")
			(roundrect_rratio 0.15)
			(net 6 "VBUS")
			(pinfunction "A")
			(pintype "passive")
		)
	)
	(footprint "antmicro-footprints:R_0402_1005Metric"
		(layer "F.Cu")
		(at 84.176 77.575)
		(descr "Resistor SMD 0402")
		(tags "resistor SMD 0402")
		(property "Reference" "R22"
			(at -1.239 2.202 180)
			(layer "F.SilkS")
			(effects
				(font
					(size 0.7 0.7)
					(thickness 0.15)
				)
				(justify left bottom)
			)
		)
		(property "Value" "R_22k_0402"
			(at -1.011843 1.772047 0)
			(layer "F.Fab")
			(effects
				(font
					(size 0.7 0.7)
					(thickness 0.15)
				)
				(justify left bottom)
			)
		)
		(property "Datasheet" "https://www.bourns.com/docs/product-datasheets/cr.pdf"
			(at 0 0 0)
			(layer "F.Fab")
			(hide yes)
			(effects
				(font
					(size 1.27 1.27)
					(thickness 0.15)
				)
			)
		)
		(property "Description" "SMD Chip Resistor, 22 kohm, ± 1%, 62.5 mW, 0402 [1005 Metric], Thick Film, General Purpose"
			(at 0 0 0)
			(layer "F.Fab")
			(hide yes)
			(effects
				(font
					(size 1.27 1.27)
					(thickness 0.15)
				)
			)
		)
		(property "MPN" "CR0402-FX-2202GLF"
			(at 0 0 0)
			(unlocked yes)
			(layer "F.Fab")
			(hide yes)
			(effects
				(font
					(size 1 1)
					(thickness 0.15)
				)
			)
		)
		(property "Manufacturer" "Bourns"
			(at 0 0 0)
			(unlocked yes)
			(layer "F.Fab")
			(hide yes)
			(effects
				(font
					(size 1 1)
					(thickness 0.15)
				)
			)
		)
		(property "License" "Apache-2.0"
			(at 0 0 0)
			(unlocked yes)
			(layer "F.Fab")
			(hide yes)
			(effects
				(font
					(size 1 1)
					(thickness 0.15)
				)
			)
		)
		(property "Author" "Antmicro"
			(at 0 0 0)
			(unlocked yes)
			(layer "F.Fab")
			(hide yes)
			(effects
				(font
					(size 1 1)
					(thickness 0.15)
				)
			)
		)
		(property "Val" "22k"
			(at 0 0 0)
			(unlocked yes)
			(layer "F.Fab")
			(hide yes)
			(effects
				(font
					(size 1 1)
					(thickness 0.15)
				)
			)
		)
		(property "Tolerance" "1%"
			(at 0 0 0)
			(unlocked yes)
			(layer "F.Fab")
			(hide yes)
			(effects
				(font
					(size 1 1)
					(thickness 0.15)
				)
			)
		)
		(sheetname "/USB PD/")
		(sheetfile "usb_pd.kicad_sch")
		(attr smd)
		(fp_rect
			(start -0.925 -0.47)
			(end 0.925 0.47)
			(stroke
				(width 0.05)
				(type default)
			)
			(fill no)
			(layer "F.CrtYd")
		)
		(fp_rect
			(start -0.5 -0.25)
			(end 0.5 0.25)
			(stroke
				(width 0.15)
				(type solid)
			)
			(fill no)
			(layer "F.Fab")
		)
		(pad "1" smd roundrect
			(at -0.48 0)
			(size 0.59 0.64)
			(layers "F.Cu" "F.Mask" "F.Paste")
			(roundrect_rratio 0.25)
			(net 53 "/USB PD/VBUS_EN")
			(pintype "passive")
		)
		(pad "2" smd roundrect
			(at 0.48 0)
			(size 0.59 0.64)
			(layers "F.Cu" "F.Mask" "F.Paste")
			(roundrect_rratio 0.25)
			(net 7 "Net-(Q1-G)")
			(pintype "passive")
		)
	)
)
